#ISCELL
  mstr_symbols cad_note *
  *
#ISCELL
  mstr_symbols intel_corp_bpage *
  *
#CELL
  mstr_discrete cap *
  page197_i1
#CELL
  w_hdl 665kr5b-1-gp *
  page197_i101
#CELL
  w_hdl 665kr2b-gp *
  page197_i109
#CELL
  w_hdl 665kr2b-gp *
  page197_i110
#CELL
  w_hdl 665kr2b-gp *
  page197_i111
#CELL
  w_hdl 665kr2b-gp *
  page197_i112
#CELL
  w_hdl 4d02r2f-gp *
  page197_i113
#CELL
  w_hdl 4d02r2f-gp *
  page197_i114
#CELL
  w_hdl 4d02r2f-gp *
  page197_i115
#CELL
  w_hdl 4d02r2f-gp *
  page197_i116
#CELL
  w_hdl 665kr5b-1-gp *
  page197_i117
#CELL
  w_hdl 665kr5b-1-gp *
  page197_i118
#CELL
  w_hdl 665kr5b-1-gp *
  page197_i119
#CELL
  w_hdl 665kr5b-1-gp *
  page197_i120
#CELL
  w_hdl 665kr5b-1-gp *
  page197_i121
#CELL
  w_hdl 665kr5b-1-gp *
  page197_i122
#CELL
  w_hdl 665kr5b-1-gp *
  page197_i123
#CELL
  mstr_discrete res *
  page197_i14
#ISCELL
  mstr_standard offpage *
  page197_i15
#ISCELL
  mstr_standard offpage *
  page197_i16
#ISCELL
  mstr_standard offpage *
  page197_i17
#CELL
  mstr_discrete cap *
  page197_i18
#CELL
  w_hdl bsl308c-h6327-gp *
  page197_i19
#ISCELL
  mstr_symbols p12v_stby *
  page197_i2
#ISCELL
  mstr_symbols gnd *
  page197_i20
#CELL
  mstr_discrete res *
  page197_i21
#ISCELL
  mstr_standard offpage *
  page197_i22
#ISCELL
  mstr_symbols p12v_nvdimm_def *
  page197_i23
#ISCELL
  mstr_standard offpage *
  page197_i24
#ISCELL
  mstr_standard offpage *
  page197_i25
#CELL
  mstr_discrete res *
  page197_i29
#ISCELL
  mstr_symbols p12v_stby *
  page197_i30
#ISCELL
  mstr_standard offpage *
  page197_i31
#ISCELL
  mstr_standard offpage *
  page197_i32
#ISCELL
  mstr_standard offpage *
  page197_i33
#CELL
  w_hdl bsl308c-h6327-gp *
  page197_i35
#ISCELL
  mstr_symbols gnd *
  page197_i36
#CELL
  mstr_discrete res *
  page197_i37
#ISCELL
  mstr_symbols p12v_nvdimm_klm *
  page197_i38
#ISCELL
  mstr_standard offpage *
  page197_i39
#ISCELL
  mstr_standard offpage *
  page197_i40
#ISCELL
  mstr_standard offpage *
  page197_i41
#CELL
  mstr_discrete cap *
  page197_i42
#CELL
  w_hdl bsl308c-h6327-gp *
  page197_i43
#ISCELL
  mstr_symbols gnd *
  page197_i44
#CELL
  mstr_discrete res *
  page197_i45
#ISCELL
  mstr_symbols p12v_stby *
  page197_i49
#CELL
  mstr_discrete res *
  page197_i50
#ISCELL
  mstr_symbols gnd *
  page197_i52
#CELL
  mstr_discrete res *
  page197_i53
#ISCELL
  mstr_symbols p12v_nvdimm_ghj *
  page197_i54
#ISCELL
  mstr_symbols gnd *
  page197_i55
#CELL
  mstr_discrete cap *
  page197_i56
#ISCELL
  mstr_symbols p12v_nvdimm_ghj *
  page197_i57
#ISCELL
  mstr_symbols gnd *
  page197_i58
#ISCELL
  mstr_symbols gnd *
  page197_i59
#CELL
  mstr_discrete res *
  page197_i6
#CELL
  mstr_discrete cap *
  page197_i60
#ISCELL
  mstr_symbols p12v_nvdimm_klm *
  page197_i61
#ISCELL
  mstr_symbols gnd *
  page197_i62
#CELL
  mstr_discrete cap *
  page197_i63
#ISCELL
  mstr_symbols p12v_nvdimm_ghj *
  page197_i64
#ISCELL
  mstr_symbols gnd *
  page197_i65
#CELL
  mstr_discrete cap *
  page197_i66
#ISCELL
  mstr_symbols p12v_nvdimm_ghj *
  page197_i67
#ISCELL
  mstr_symbols gnd *
  page197_i68
#CELL
  mstr_discrete cap *
  page197_i69
#ISCELL
  mstr_symbols gnd *
  page197_i70
#CELL
  mstr_discrete cap *
  page197_i71
#CELL
  mstr_discrete cap *
  page197_i72
#ISCELL
  mstr_symbols p12v_nvdimm_klm *
  page197_i73
#ISCELL
  mstr_symbols gnd *
  page197_i74
#CELL
  mstr_discrete cap *
  page197_i75
#ISCELL
  mstr_symbols p12v_nvdimm_klm *
  page197_i76
#ISCELL
  mstr_symbols gnd *
  page197_i77
#CELL
  mstr_discrete cap *
  page197_i78
#ISCELL
  mstr_symbols p12v_nvdimm_def *
  page197_i79
#CELL
  mstr_discrete cap *
  page197_i8
#ISCELL
  mstr_symbols gnd *
  page197_i80
#CELL
  mstr_discrete cap *
  page197_i81
#ISCELL
  mstr_symbols p12v_nvdimm_abc *
  page197_i82
#ISCELL
  mstr_symbols gnd *
  page197_i83
#CELL
  mstr_discrete cap *
  page197_i84
#ISCELL
  mstr_symbols p12v_nvdimm_abc *
  page197_i85
#ISCELL
  mstr_symbols p12v_nvdimm_def *
  page197_i86
#ISCELL
  mstr_symbols gnd *
  page197_i87
#CELL
  mstr_discrete cap *
  page197_i88
#ISCELL
  mstr_symbols p12v_nvdimm_def *
  page197_i89
#ISCELL
  mstr_symbols p12v_stby *
  page197_i9
#ISCELL
  mstr_symbols p12v_nvdimm_abc *
  page197_i90
#CELL
  w_hdl bsl308c-h6327-gp *
  page197_i91
#ISCELL
  mstr_symbols p12v_nvdimm_abc *
  page197_i92
